(kicad_pcb
	(version 20260206)
	(generator "pcbnew")
	(generator_version "10.0")
	(general
		(thickness 1.6)
		(legacy_teardrops no)
	)
	(paper "A4")
	(title_block
		(title "03242023_DA0F0TMBIJ0_F0T_Motherboard_J_brd_V01_OCP.brd")
		(comment 1 "Grand Teton / footprints 3750-3750 of 6105")
	)
	(layers
		(0 "F.Cu" signal "TOP")
		(4 "In1.Cu" signal "GND")
		(6 "In2.Cu" signal "IN1")
		(8 "In3.Cu" signal "GND1")
		(10 "In4.Cu" signal "IN2")
		(12 "In5.Cu" signal "GND2")
		(14 "In6.Cu" signal "IN3")
		(16 "In7.Cu" signal "GND3")
		(18 "In8.Cu" signal "VCC")
		(20 "In9.Cu" signal "VCC1")
		(22 "In10.Cu" signal "GND4")
		(24 "In11.Cu" signal "IN4")
		(26 "In12.Cu" signal "GND5")
		(28 "In13.Cu" signal "IN5")
		(30 "In14.Cu" signal "GND6")
		(32 "In15.Cu" signal "IN6")
		(34 "In16.Cu" signal "GND7")
		(2 "B.Cu" signal "BOTTOM")
		(9 "F.Adhes" user "F.Adhesive")
		(11 "B.Adhes" user "B.Adhesive")
		(13 "F.Paste" user "Package Geometry/Pastemask Top")
		(15 "B.Paste" user "Package Geometry/Pastemask Bottom")
		(5 "F.SilkS" user "Ref Des/Silkscreen Top")
		(7 "B.SilkS" user "Ref Des/Silkscreen Bottom")
		(1 "F.Mask" user "Board Geometry/Soldermask Top")
		(3 "B.Mask" user "Board Geometry/Soldermask Bottom")
		(17 "Dwgs.User" user "User.Drawings")
		(19 "Cmts.User" user "User.Comments")
		(21 "Eco1.User" user "User.Eco1")
		(23 "Eco2.User" user "User.Eco2")
		(25 "Edge.Cuts" user "Board Geometry/Outline")
		(27 "Margin" user)
		(31 "F.CrtYd" user "Package Geometry/Place Bound Top")
		(29 "B.CrtYd" user "Package Geometry/Place Bound Bottom")
		(35 "F.Fab" user "Ref Des/Assembly Top")
		(33 "B.Fab" user "Ref Des/Assembly Bottom")
	)
	(footprint ""
		(layer "F.Cu")
		(at 177.694082 -28.937712 -90)
		(property "Reference" "PU299"
			(at -3.695446 10.633202 0)
			(unlocked yes)
			(layer "F.SilkS")
			(effects
				(font
					(size 0.7874 0.5842)
					(thickness 0.1524)
				)
				(justify left)
			)
		)
		(property "Value" ""
			(at 0 0 270)
			(layer "F.Fab")
			(effects
				(font
					(size 1.27 1.27)
				)
			)
		)
		(duplicate_pad_numbers_are_jumpers no)
		(fp_line
			(start -1.549908 2.549906)
			(end -0.753872 2.549906)
			(stroke
				(width 0.1524)
				(type default)
			)
			(layer "F.SilkS")
		)
		(fp_line
			(start -0.245872 2.549906)
			(end 0.245872 2.549906)
			(stroke
				(width 0.1524)
				(type default)
			)
			(layer "F.SilkS")
		)
		(fp_line
			(start 0.753872 2.549906)
			(end 1.549908 2.549906)
			(stroke
				(width 0.1524)
				(type default)
			)
			(layer "F.SilkS")
		)
		(fp_line
			(start 1.549908 2.549906)
			(end 1.549908 2.253996)
			(stroke
				(width 0.1524)
				(type default)
			)
			(layer "F.SilkS")
		)
		(fp_line
			(start -1.549908 2.253996)
			(end -1.549908 2.549906)
			(stroke
				(width 0.1524)
				(type default)
			)
			(layer "F.SilkS")
		)
		(fp_line
			(start 1.549908 -2.253996)
			(end 1.549908 -2.549906)
			(stroke
				(width 0.1524)
				(type default)
			)
			(layer "F.SilkS")
		)
		(fp_line
			(start -1.549908 -2.549906)
			(end -1.549908 -2.251964)
			(stroke
				(width 0.1524)
				(type default)
			)
			(layer "F.SilkS")
		)
		(fp_line
			(start -0.752094 -2.549906)
			(end -1.549908 -2.549906)
			(stroke
				(width 0.1524)
				(type default)
			)
			(layer "F.SilkS")
		)
		(fp_line
			(start 0.2413 -2.549906)
			(end -0.2413 -2.549906)
			(stroke
				(width 0.1524)
				(type default)
			)
			(layer "F.SilkS")
		)
		(fp_line
			(start 1.549908 -2.549906)
			(end 0.752094 -2.549906)
			(stroke
				(width 0.1524)
				(type default)
			)
			(layer "F.SilkS")
		)
		(fp_poly
			(pts
				(xy -2.7432 -1.574292) (xy -2.7432 -2.4257) (xy -1.891538 -1.999996)
			)
			(stroke
				(width 0)
				(type default)
			)
			(fill yes)
			(layer "F.SilkS")
		)
		(fp_line
			(start -1.549908 2.549906)
			(end 1.549908 2.549906)
			(stroke
				(width 0.1)
				(type default)
			)
			(layer "F.Fab")
		)
		(fp_line
			(start 1.549908 2.549906)
			(end 1.549908 -2.549906)
			(stroke
				(width 0.1)
				(type default)
			)
			(layer "F.Fab")
		)
		(fp_line
			(start -1.549908 -2.549906)
			(end -1.549908 2.549906)
			(stroke
				(width 0.1)
				(type default)
			)
			(layer "F.Fab")
		)
		(fp_line
			(start 1.549908 -2.549906)
			(end -1.549908 -2.549906)
			(stroke
				(width 0.1)
				(type default)
			)
			(layer "F.Fab")
		)
		(fp_poly
			(pts
				(xy -1.891538 -1.999996) (xy -2.7432 -1.574292) (xy -2.7432 -2.4257)
			)
			(stroke
				(width 0)
				(type default)
			)
			(fill yes)
			(layer "F.Fab")
		)
		(fp_text user "11"
			(at 2.959354 5.367782 0)
			(unlocked yes)
			(layer "F.SilkS")
			(effects
				(font
					(size 0.635 0.4064)
					(thickness 0.1524)
				)
			)
		)
		(fp_text user "10"
			(at -2.087626 2.863342 0)
			(unlocked yes)
			(layer "F.SilkS")
			(effects
				(font
					(size 0.635 0.4064)
					(thickness 0.1524)
				)
			)
		)
		(fp_text user "9"
			(at -2.478786 1.346962 180)
			(unlocked yes)
			(layer "F.SilkS")
			(effects
				(font
					(size 0.635 0.4064)
					(thickness 0.1524)
				)
			)
		)
		(fp_text user "12"
			(at 3.713734 0.864362 0)
			(unlocked yes)
			(layer "F.SilkS")
			(effects
				(font
					(size 0.635 0.4064)
					(thickness 0.1524)
				)
			)
		)
		(fp_text user "20"
			(at 1.641094 -4.164838 0)
			(unlocked yes)
			(layer "F.SilkS")
			(effects
				(font
					(size 0.635 0.4064)
					(thickness 0.1524)
				)
			)
		)
		(fp_text user "21_22"
			(at -1.886966 -4.454398 0)
			(unlocked yes)
			(layer "F.SilkS")
			(effects
				(font
					(size 0.635 0.4064)
					(thickness 0.1524)
				)
			)
		)
		(fp_text user "11"
			(at 1.1938 3.329432 270)
			(unlocked yes)
			(layer "F.Fab")
			(effects
				(font
					(size 0.635 0.4064)
					(thickness 0.1524)
				)
			)
		)
		(fp_text user "10"
			(at -1.4224 3.253232 270)
			(unlocked yes)
			(layer "F.Fab")
			(effects
				(font
					(size 0.635 0.4064)
					(thickness 0.1524)
				)
			)
		)
		(fp_text user "12"
			(at 2.207768 2.7178 180)
			(unlocked yes)
			(layer "F.Fab")
			(effects
				(font
					(size 0.635 0.4064)
					(thickness 0.1524)
				)
			)
		)
		(fp_text user "9"
			(at -2.338832 2.5908 180)
			(unlocked yes)
			(layer "F.Fab")
			(effects
				(font
					(size 0.635 0.4064)
					(thickness 0.1524)
				)
			)
		)
		(fp_text user "20"
			(at 2.055368 -2.7686 180)
			(unlocked yes)
			(layer "F.Fab")
			(effects
				(font
					(size 0.635 0.4064)
					(thickness 0.1524)
				)
			)
		)
		(fp_text user "21_22"
			(at -0.0762 -3.401568 270)
			(unlocked yes)
			(layer "F.Fab")
			(effects
				(font
					(size 0.635 0.4064)
					(thickness 0.1524)
				)
			)
		)
		(pad "1" smd circle
			(at -1.374902 -1.999996 180)
			(size 0 0)
			(layers "F.Cu" "F.Mask" "F.Paste")
			(net "P12V_SCM_EN_R2")
		)
		(pad "2" smd rect
			(at -1.400048 -1.500124 180)
			(size 0.254 0.8128)
			(layers "F.Cu" "F.Mask" "F.Paste")
			(net "GND")
		)
		(pad "3" smd rect
			(at -1.400048 -0.999998 180)
			(size 0.254 0.8128)
			(layers "F.Cu" "F.Mask" "F.Paste")
			(net "GND")
		)
		(pad "4" smd rect
			(at -1.400048 -0.499872 180)
			(size 0.254 0.8128)
			(layers "F.Cu" "F.Mask" "F.Paste")
			(net "P12V_SCM_TIMER")
		)
		(pad "5" smd rect
			(at -1.400048 0 180)
			(size 0.254 0.8128)
			(layers "F.Cu" "F.Mask" "F.Paste")
			(net "P12V_SCM_ISET")
		)
		(pad "6" smd rect
			(at -1.400048 0.499872 180)
			(size 0.254 0.8128)
			(layers "F.Cu" "F.Mask" "F.Paste")
			(net "P12V_SCM_SS")
		)
		(pad "7" smd rect
			(at -1.400048 0.999998 180)
			(size 0.254 0.8128)
			(layers "F.Cu" "F.Mask" "F.Paste")
			(net "GND")
		)
		(pad "8" smd rect
			(at -1.400048 1.500124 180)
			(size 0.254 0.8128)
			(layers "F.Cu" "F.Mask" "F.Paste")
			(net "P12V_SCM_IMON")
		)
		(pad "9" smd rect
			(at -1.400048 1.999996 180)
			(size 0.254 0.8128)
			(layers "F.Cu" "F.Mask" "F.Paste")
			(net "P12V_SCM_FLTB_N")
		)
		(pad "10" smd rect
			(at -0.499872 2.400046 270)
			(size 0.254 0.8128)
			(layers "F.Cu" "F.Mask" "F.Paste")
			(net "HP_LVC3_SCM_HSC_PWRGD_R")
		)
		(pad "11" smd rect
			(at 0.499872 2.400046 270)
			(size 0.254 0.8128)
			(layers "F.Cu" "F.Mask" "F.Paste")
			(net "P12V_SCM_OV_FB")
		)
		(pad "12" smd rect
			(at 1.400048 1.999996 180)
			(size 0.254 0.8128)
			(layers "F.Cu" "F.Mask" "F.Paste")
			(net "P12V_SCM_AVIN_PD")
		)
		(pad "13" smd rect
			(at 1.400048 1.500124 180)
			(size 0.254 0.8128)
			(layers "F.Cu" "F.Mask" "F.Paste")
			(net "P12V_SCM_R")
		)
		(pad "14" smd rect
			(at 1.400048 0.999998 180)
			(size 0.254 0.8128)
			(layers "F.Cu" "F.Mask" "F.Paste")
			(net "P12V_SCM_R")
		)
		(pad "15" smd rect
			(at 1.400048 0.499872 180)
			(size 0.254 0.8128)
			(layers "F.Cu" "F.Mask" "F.Paste")
			(net "P12V_SCM_R")
		)
		(pad "16" smd rect
			(at 1.400048 0 180)
			(size 0.254 0.8128)
			(layers "F.Cu" "F.Mask" "F.Paste")
			(net "P12V_SCM_R")
		)
		(pad "17" smd rect
			(at 1.400048 -0.499872 180)
			(size 0.254 0.8128)
			(layers "F.Cu" "F.Mask" "F.Paste")
			(net "P12V_SCM_R")
		)
		(pad "18" smd rect
			(at 1.400048 -0.999998 180)
			(size 0.254 0.8128)
			(layers "F.Cu" "F.Mask" "F.Paste")
			(net "P12V_SCM_R")
		)
		(pad "19" smd rect
			(at 1.400048 -1.500124 180)
			(size 0.254 0.8128)
			(layers "F.Cu" "F.Mask" "F.Paste")
			(net "P12V_SCM_R")
		)
		(pad "20" smd rect
			(at 1.400048 -1.999996 180)
			(size 0.254 0.8128)
			(layers "F.Cu" "F.Mask" "F.Paste")
			(net "P12V_SCM_R")
		)
		(pad "21_22" smd circle
			(at 0.499872 -2.337562 180)
			(size 0 0)
			(layers "F.Cu" "F.Mask" "F.Paste")
			(net "P12V_AUX")
		)
		(pad "23" smd rect
			(at 0 -1.100074 180)
			(size 0.254 1.27)
			(layers "F.Cu" "F.Mask" "F.Paste")
			(net "P12V_AUX")
		)
		(pad "24" smd rect
			(at 0 -0.199898 180)
			(size 0.254 1.27)
			(layers "F.Cu" "F.Mask" "F.Paste")
			(net "P12V_AUX")
		)
		(pad "25" smd rect
			(at 0 0.700024 180)
			(size 0.254 1.27)
			(layers "F.Cu" "F.Mask" "F.Paste")
			(net "P12V_AUX")
		)
		(pad "26" smd rect
			(at 0 1.599946 180)
			(size 0.254 1.27)
			(layers "F.Cu" "F.Mask" "F.Paste")
			(net "P12V_AUX")
		)
	)
)
